# BASEBOARD_FAB2 (Tioga Pass) — schematic netlist excerpt (pin names and nets, part order shuffled) for the footprints in the layout excerpt that follows; sources: Cadence DE-HDL packaged netlist, KiCad conversion of Wiwynn_Tioga_Pass_MB.brd

C1C16  CAP  220PF 50V 10% X7R  pkg 0402LF  page 206 : A = VSENSE_PVSA_CPU1_BVSP ; B = VSENSE_PVSA_CPU1_N
R8G15  RES  0.0 5% EMPTY  pkg 0402  page 189 : A = JTAG_PCH_GBE_CLK ; B = JTAG_TCK
C4G2  CAP  10UF 16V 10% X6S  pkg 0805  page 233 : A = VR_FET_SW_P12V_STBY_PVPP_GHJ ; B = GND

(kicad_pcb
	(version 20260206)
	(generator "pcbnew")
	(generator_version "10.0")
	(general
		(thickness 1.6)
		(legacy_teardrops no)
	)
	(paper "A4")
	(title_block
		(title "Wiwynn_Tioga_Pass_MB.brd")
		(comment 1 "Tioga Pass / footprints 38-40 of 4770")
	)
	(layers
		(0 "F.Cu" signal "TOP")
		(4 "In1.Cu" signal "L2GND")
		(6 "In2.Cu" signal "L3")
		(8 "In3.Cu" signal "L4GND")
		(10 "In4.Cu" signal "L5")
		(12 "In5.Cu" signal "L6GND")
		(14 "In6.Cu" signal "L7VCC")
		(16 "In7.Cu" signal "L8VCC")
		(18 "In8.Cu" signal "L9GND")
		(20 "In9.Cu" signal "L10")
		(22 "In10.Cu" signal "L11GND")
		(24 "In11.Cu" signal "L12")
		(26 "In12.Cu" signal "L13GND")
		(2 "B.Cu" signal "BOTTOM")
		(9 "F.Adhes" user "F.Adhesive")
		(11 "B.Adhes" user "B.Adhesive")
		(13 "F.Paste" user "Package Geometry/Pastemask Top")
		(15 "B.Paste" user "Package Geometry/Pastemask Bottom")
		(5 "F.SilkS" user "Ref Des/Silkscreen Top")
		(7 "B.SilkS" user "Ref Des/Silkscreen Bottom")
		(1 "F.Mask" user "Board Geometry/Soldermask Top")
		(3 "B.Mask" user "Board Geometry/Soldermask Bottom")
		(17 "Dwgs.User" user "User.Drawings")
		(19 "Cmts.User" user "User.Comments")
		(21 "Eco1.User" user "User.Eco1")
		(23 "Eco2.User" user "User.Eco2")
		(25 "Edge.Cuts" user "Board Geometry/Outline")
		(27 "Margin" user)
		(31 "F.CrtYd" user "Package Geometry/Place Bound Top")
		(29 "B.CrtYd" user "Package Geometry/Place Bound Bottom")
		(35 "F.Fab" user "Ref Des/Assembly Top")
		(33 "B.Fab" user "Ref Des/Assembly Bottom")
	)
	(footprint ""
		(layer "F.Cu")
		(at 397.3576 -0.2286)
		(property "Reference" "R8G15"
			(at 0 0 0)
			(layer "F.SilkS")
			(hide yes)
			(effects
				(font
					(size 1.27 1.27)
				)
			)
		)
		(property "Value" ""
			(at 0 0 0)
			(layer "F.Fab")
			(effects
				(font
					(size 1.27 1.27)
				)
			)
		)
		(duplicate_pad_numbers_are_jumpers no)
		(fp_poly
			(pts
				(xy -0.2794 -0.1016) (xy 0.2794 -0.1016) (xy 0.2794 0.9906) (xy -0.2794 0.9906)
			)
			(stroke
				(width 0)
				(type default)
			)
			(fill no)
			(layer "F.CrtYd")
		)
		(fp_line
			(start -0.2794 -0.1016)
			(end -0.2794 0.9906)
			(stroke
				(width 0.1)
				(type default)
			)
			(layer "F.Fab")
		)
		(fp_line
			(start -0.2794 0.9906)
			(end 0.2794 0.9906)
			(stroke
				(width 0.1)
				(type default)
			)
			(layer "F.Fab")
		)
		(fp_line
			(start 0.2794 -0.1016)
			(end -0.2794 -0.1016)
			(stroke
				(width 0.1)
				(type default)
			)
			(layer "F.Fab")
		)
		(fp_line
			(start 0.2794 0.9906)
			(end 0.2794 -0.1016)
			(stroke
				(width 0.1)
				(type default)
			)
			(layer "F.Fab")
		)
		(pad "1" smd rect
			(at 0 0)
			(size 0.508 0.508)
			(layers "F.Cu" "F.Mask" "F.Paste")
			(net "JTAG_PCH_GBE_CLK")
		)
		(pad "2" smd rect
			(at 0 0.889)
			(size 0.508 0.508)
			(layers "F.Cu" "F.Mask" "F.Paste")
			(net "JTAG_TCK")
		)
		(zone
			(layer "F.Cu")
			(hatch none 0.5)
			(connect_pads
				(clearance 0)
			)
			(min_thickness 0.25)
			(keepout
				(tracks allowed)
				(vias not_allowed)
				(pads allowed)
				(copperpour not_allowed)
				(footprints allowed)
			)
			(placement
				(enabled no)
				(sheetname "")
			)
			(fill
				(thermal_gap 0.5)
				(thermal_bridge_width 0.5)
				(island_removal_mode 0)
			)
			(polygon
				(pts
					(xy 397.1036 0.0254) (xy 397.6116 0.0254) (xy 397.6116 0.4064) (xy 397.1036 0.4064)
				)
			)
		)
		(zone
			(layer "F.Cu")
			(hatch none 0.5)
			(connect_pads
				(clearance 0)
			)
			(min_thickness 0.25)
			(keepout
				(tracks not_allowed)
				(vias allowed)
				(pads allowed)
				(copperpour not_allowed)
				(footprints allowed)
			)
			(placement
				(enabled no)
				(sheetname "")
			)
			(fill
				(thermal_gap 0.5)
				(thermal_bridge_width 0.5)
				(island_removal_mode 0)
			)
			(polygon
				(pts
					(xy 397.1036 0.4064) (xy 397.6116 0.4064) (xy 397.6116 0.0254) (xy 397.1036 0.0254)
				)
			)
		)
	)
	(footprint ""
		(layer "F.Cu")
		(at 23.366984 -94.938596 180)
		(property "Reference" "C1C16"
			(at 0 0 180)
			(layer "F.SilkS")
			(hide yes)
			(effects
				(font
					(size 1.27 1.27)
				)
			)
		)
		(property "Value" ""
			(at 0 0 180)
			(layer "F.Fab")
			(effects
				(font
					(size 1.27 1.27)
				)
			)
		)
		(duplicate_pad_numbers_are_jumpers no)
		(fp_rect
			(start 0.3048 -0.1016)
			(end -0.3048 0.9906)
			(stroke
				(width 0)
				(type default)
			)
			(fill no)
			(layer "F.CrtYd")
		)
		(fp_line
			(start 0.3048 0.9906)
			(end 0.3048 -0.1016)
			(stroke
				(width 0.1)
				(type default)
			)
			(layer "F.Fab")
		)
		(fp_line
			(start 0.3048 -0.1016)
			(end -0.3048 -0.1016)
			(stroke
				(width 0.1)
				(type default)
			)
			(layer "F.Fab")
		)
		(fp_line
			(start -0.3048 0.9906)
			(end 0.3048 0.9906)
			(stroke
				(width 0.1)
				(type default)
			)
			(layer "F.Fab")
		)
		(fp_line
			(start -0.3048 -0.1016)
			(end -0.3048 0.9906)
			(stroke
				(width 0.1)
				(type default)
			)
			(layer "F.Fab")
		)
		(pad "1" smd rect
			(at 0 0 180)
			(size 0.508 0.508)
			(layers "F.Cu" "F.Mask" "F.Paste")
			(net "VSENSE_PVSA_CPU1_BVSP")
		)
		(pad "2" smd rect
			(at 0 0.889 180)
			(size 0.508 0.508)
			(layers "F.Cu" "F.Mask" "F.Paste")
			(net "VSENSE_PVSA_CPU1_N")
		)
		(zone
			(layer "F.Cu")
			(hatch none 0.5)
			(connect_pads
				(clearance 0)
			)
			(min_thickness 0.25)
			(keepout
				(tracks not_allowed)
				(vias allowed)
				(pads allowed)
				(copperpour not_allowed)
				(footprints allowed)
			)
			(placement
				(enabled no)
				(sheetname "")
			)
			(fill
				(thermal_gap 0.5)
				(thermal_bridge_width 0.5)
				(island_removal_mode 0)
			)
			(polygon
				(pts
					(xy 23.112984 -95.192596) (xy 23.620984 -95.192596) (xy 23.620984 -95.573596) (xy 23.112984 -95.573596)
				)
			)
		)
		(zone
			(layer "F.Cu")
			(hatch none 0.5)
			(connect_pads
				(clearance 0)
			)
			(min_thickness 0.25)
			(keepout
				(tracks allowed)
				(vias not_allowed)
				(pads allowed)
				(copperpour not_allowed)
				(footprints allowed)
			)
			(placement
				(enabled no)
				(sheetname "")
			)
			(fill
				(thermal_gap 0.5)
				(thermal_bridge_width 0.5)
				(island_removal_mode 0)
			)
			(polygon
				(pts
					(xy 23.112984 -95.192596) (xy 23.620984 -95.192596) (xy 23.620984 -95.573596) (xy 23.112984 -95.573596)
				)
			)
		)
	)
	(footprint ""
		(layer "F.Cu")
		(at 183.261 -13.335 180)
		(property "Reference" "C4G2"
			(at 0 0 180)
			(layer "F.SilkS")
			(hide yes)
			(effects
				(font
					(size 1.27 1.27)
				)
			)
		)
		(property "Value" ""
			(at 0 0 180)
			(layer "F.Fab")
			(effects
				(font
					(size 1.27 1.27)
				)
			)
		)
		(duplicate_pad_numbers_are_jumpers no)
		(fp_poly
			(pts
				(xy -0.7239 -0.2159) (xy 0.7239 -0.2159) (xy 0.7239 1.9939) (xy -0.7239 1.9939)
			)
			(stroke
				(width 0)
				(type default)
			)
			(fill no)
			(layer "F.CrtYd")
		)
		(fp_line
			(start 0.7239 1.9939)
			(end 0.7239 -0.2159)
			(stroke
				(width 0.1)
				(type default)
			)
			(layer "F.Fab")
		)
		(fp_line
			(start 0.7239 -0.2159)
			(end -0.7239 -0.2159)
			(stroke
				(width 0.1)
				(type default)
			)
			(layer "F.Fab")
		)
		(fp_line
			(start -0.7239 1.9939)
			(end 0.7239 1.9939)
			(stroke
				(width 0.1)
				(type default)
			)
			(layer "F.Fab")
		)
		(fp_line
			(start -0.7239 -0.2159)
			(end -0.7239 1.9939)
			(stroke
				(width 0.1)
				(type default)
			)
			(layer "F.Fab")
		)
		(pad "1" smd rect
			(at 0 0 180)
			(size 1.27 1.016)
			(layers "F.Cu" "F.Mask" "F.Paste")
			(net "VR_FET_SW_P12V_STBY_PVPP_GHJ")
		)
		(pad "2" smd rect
			(at 0 1.778 180)
			(size 1.27 1.016)
			(layers "F.Cu" "F.Mask" "F.Paste")
			(net "GND")
		)
		(zone
			(layer "F.Cu")
			(hatch none 0.5)
			(connect_pads
				(clearance 0)
			)
			(min_thickness 0.25)
			(keepout
				(tracks not_allowed)
				(vias allowed)
				(pads allowed)
				(copperpour not_allowed)
				(footprints allowed)
			)
			(placement
				(enabled no)
				(sheetname "")
			)
			(fill
				(thermal_gap 0.5)
				(thermal_bridge_width 0.5)
				(island_removal_mode 0)
			)
			(polygon
				(pts
					(xy 183.896 -13.843) (xy 182.626 -13.843) (xy 182.626 -14.605) (xy 183.896 -14.605)
				)
			)
		)
	)
)
